(kicad_pcb
	(version 20260206)
	(generator "pcbnew")
	(generator_version "10.0")
	(general
		(thickness 1.6)
		(legacy_teardrops no)
	)
	(paper "A4")
	(title_block
		(title "03242023_DA0F0TMBIJ0_F0T_Motherboard_J_brd_V01_OCP.brd")
		(comment 1 "Grand Teton / footprints 3876-3883 of 6105")
	)
	(layers
		(0 "F.Cu" signal "TOP")
		(4 "In1.Cu" signal "GND")
		(6 "In2.Cu" signal "IN1")
		(8 "In3.Cu" signal "GND1")
		(10 "In4.Cu" signal "IN2")
		(12 "In5.Cu" signal "GND2")
		(14 "In6.Cu" signal "IN3")
		(16 "In7.Cu" signal "GND3")
		(18 "In8.Cu" signal "VCC")
		(20 "In9.Cu" signal "VCC1")
		(22 "In10.Cu" signal "GND4")
		(24 "In11.Cu" signal "IN4")
		(26 "In12.Cu" signal "GND5")
		(28 "In13.Cu" signal "IN5")
		(30 "In14.Cu" signal "GND6")
		(32 "In15.Cu" signal "IN6")
		(34 "In16.Cu" signal "GND7")
		(2 "B.Cu" signal "BOTTOM")
		(9 "F.Adhes" user "F.Adhesive")
		(11 "B.Adhes" user "B.Adhesive")
		(13 "F.Paste" user "Package Geometry/Pastemask Top")
		(15 "B.Paste" user "Package Geometry/Pastemask Bottom")
		(5 "F.SilkS" user "Ref Des/Silkscreen Top")
		(7 "B.SilkS" user "Ref Des/Silkscreen Bottom")
		(1 "F.Mask" user "Board Geometry/Soldermask Top")
		(3 "B.Mask" user "Board Geometry/Soldermask Bottom")
		(17 "Dwgs.User" user "User.Drawings")
		(19 "Cmts.User" user "User.Comments")
		(21 "Eco1.User" user "User.Eco1")
		(23 "Eco2.User" user "User.Eco2")
		(25 "Edge.Cuts" user "Board Geometry/Outline")
		(27 "Margin" user)
		(31 "F.CrtYd" user "Package Geometry/Place Bound Top")
		(29 "B.CrtYd" user "Package Geometry/Place Bound Bottom")
		(35 "F.Fab" user "Ref Des/Assembly Top")
		(33 "B.Fab" user "Ref Des/Assembly Bottom")
	)
	(footprint ""
		(layer "F.Cu")
		(at 125.53696 -335.176368)
		(property "Reference" "PC527_P1_4"
			(at 0 0 0)
			(layer "F.SilkS")
			(hide yes)
			(effects
				(font
					(size 1.27 1.27)
				)
			)
		)
		(property "Value" ""
			(at 0 0 0)
			(layer "F.Fab")
			(effects
				(font
					(size 1.27 1.27)
				)
			)
		)
		(duplicate_pad_numbers_are_jumpers no)
		(fp_line
			(start -0.7874 -0.4064)
			(end 0.7874 -0.4064)
			(stroke
				(width 0.1524)
				(type default)
			)
			(layer "F.SilkS")
		)
		(fp_line
			(start -0.7874 0.4064)
			(end -0.7874 -0.4064)
			(stroke
				(width 0.1524)
				(type default)
			)
			(layer "F.SilkS")
		)
		(fp_line
			(start 0.7874 -0.4064)
			(end 0.7874 0.4064)
			(stroke
				(width 0.1524)
				(type default)
			)
			(layer "F.SilkS")
		)
		(fp_line
			(start 0.7874 0.4064)
			(end -0.7874 0.4064)
			(stroke
				(width 0.1524)
				(type default)
			)
			(layer "F.SilkS")
		)
		(fp_line
			(start -0.67945 -0.305054)
			(end -0.12065 -0.305054)
			(stroke
				(width 0.1)
				(type default)
			)
			(layer "F.Fab")
		)
		(fp_line
			(start -0.67945 0.3048)
			(end -0.67945 -0.305054)
			(stroke
				(width 0.1)
				(type default)
			)
			(layer "F.Fab")
		)
		(fp_line
			(start -0.12065 -0.305054)
			(end -0.12065 -0.2794)
			(stroke
				(width 0.1)
				(type default)
			)
			(layer "F.Fab")
		)
		(fp_line
			(start -0.12065 -0.2794)
			(end 0.12065 -0.2794)
			(stroke
				(width 0.1)
				(type default)
			)
			(layer "F.Fab")
		)
		(fp_line
			(start -0.12065 0.2794)
			(end -0.12065 0.3048)
			(stroke
				(width 0.1)
				(type default)
			)
			(layer "F.Fab")
		)
		(fp_line
			(start -0.12065 0.3048)
			(end -0.67945 0.3048)
			(stroke
				(width 0.1)
				(type default)
			)
			(layer "F.Fab")
		)
		(fp_line
			(start 0.120396 0.2794)
			(end -0.12065 0.2794)
			(stroke
				(width 0.1)
				(type default)
			)
			(layer "F.Fab")
		)
		(fp_line
			(start 0.120396 0.3048)
			(end 0.120396 0.2794)
			(stroke
				(width 0.1)
				(type default)
			)
			(layer "F.Fab")
		)
		(fp_line
			(start 0.12065 -0.3048)
			(end 0.67945 -0.3048)
			(stroke
				(width 0.1)
				(type default)
			)
			(layer "F.Fab")
		)
		(fp_line
			(start 0.12065 -0.2794)
			(end 0.12065 -0.3048)
			(stroke
				(width 0.1)
				(type default)
			)
			(layer "F.Fab")
		)
		(fp_line
			(start 0.67945 -0.3048)
			(end 0.67945 0.3048)
			(stroke
				(width 0.1)
				(type default)
			)
			(layer "F.Fab")
		)
		(fp_line
			(start 0.67945 0.3048)
			(end 0.120396 0.3048)
			(stroke
				(width 0.1)
				(type default)
			)
			(layer "F.Fab")
		)
		(pad "1" smd circle
			(at -0.40005 0)
			(size 0 0)
			(layers "F.Cu" "F.Mask" "F.Paste")
			(net "SW_P12V_PVCCIN_CPU1_FLT")
		)
		(pad "2" smd circle
			(at 0.40005 0)
			(size 0 0)
			(layers "F.Cu" "F.Mask" "F.Paste")
			(net "GND")
		)
	)
	(footprint ""
		(layer "F.Cu")
		(at 304.869088 -402.371052 -90)
		(property "Reference" "C1579"
			(at 0 0 270)
			(layer "F.SilkS")
			(hide yes)
			(effects
				(font
					(size 1.27 1.27)
				)
			)
		)
		(property "Value" ""
			(at 0 0 270)
			(layer "F.Fab")
			(effects
				(font
					(size 1.27 1.27)
				)
			)
		)
		(duplicate_pad_numbers_are_jumpers no)
		(fp_line
			(start -0.299974 0.150114)
			(end -0.299974 -0.150114)
			(stroke
				(width 0.1)
				(type default)
			)
			(layer "F.Fab")
		)
		(fp_line
			(start 0.299974 0.150114)
			(end -0.299974 0.150114)
			(stroke
				(width 0.1)
				(type default)
			)
			(layer "F.Fab")
		)
		(fp_line
			(start -0.299974 -0.150114)
			(end 0.299974 -0.150114)
			(stroke
				(width 0.1)
				(type default)
			)
			(layer "F.Fab")
		)
		(fp_line
			(start 0.299974 -0.150114)
			(end 0.299974 0.150114)
			(stroke
				(width 0.1)
				(type default)
			)
			(layer "F.Fab")
		)
		(pad "1" smd rect
			(at -0.2667 0 270)
			(size 0.3048 0.381)
			(layers "F.Cu" "F.Mask" "F.Paste")
			(net "P5E_CPU0_PE4_TX_C_DP<0>")
		)
		(pad "2" smd rect
			(at 0.2667 0 270)
			(size 0.3048 0.381)
			(layers "F.Cu" "F.Mask" "F.Paste")
			(net "P5E_CPU0_PE4_TX_DP<0>")
		)
	)
	(footprint ""
		(layer "F.Cu")
		(at 109.063282 -406.058116 90)
		(property "Reference" "R3497"
			(at 0 0 90)
			(layer "F.SilkS")
			(hide yes)
			(effects
				(font
					(size 1.27 1.27)
				)
			)
		)
		(property "Value" ""
			(at 0 0 90)
			(layer "F.Fab")
			(effects
				(font
					(size 1.27 1.27)
				)
			)
		)
		(duplicate_pad_numbers_are_jumpers no)
		(fp_line
			(start 0.7874 -0.4064)
			(end 0.7874 0.4064)
			(stroke
				(width 0.1524)
				(type default)
			)
			(layer "F.SilkS")
		)
		(fp_line
			(start -0.7874 -0.4064)
			(end 0.7874 -0.4064)
			(stroke
				(width 0.1524)
				(type default)
			)
			(layer "F.SilkS")
		)
		(fp_line
			(start 0.7874 0.4064)
			(end -0.7874 0.4064)
			(stroke
				(width 0.1524)
				(type default)
			)
			(layer "F.SilkS")
		)
		(fp_line
			(start -0.7874 0.4064)
			(end -0.7874 -0.4064)
			(stroke
				(width 0.1524)
				(type default)
			)
			(layer "F.SilkS")
		)
		(fp_line
			(start -0.12065 -0.305054)
			(end -0.12065 -0.2794)
			(stroke
				(width 0.1)
				(type default)
			)
			(layer "F.Fab")
		)
		(fp_line
			(start -0.67945 -0.305054)
			(end -0.12065 -0.305054)
			(stroke
				(width 0.1)
				(type default)
			)
			(layer "F.Fab")
		)
		(fp_line
			(start 0.67945 -0.3048)
			(end 0.67945 0.3048)
			(stroke
				(width 0.1)
				(type default)
			)
			(layer "F.Fab")
		)
		(fp_line
			(start 0.12065 -0.3048)
			(end 0.67945 -0.3048)
			(stroke
				(width 0.1)
				(type default)
			)
			(layer "F.Fab")
		)
		(fp_line
			(start 0.12065 -0.2794)
			(end 0.12065 -0.3048)
			(stroke
				(width 0.1)
				(type default)
			)
			(layer "F.Fab")
		)
		(fp_line
			(start -0.12065 -0.2794)
			(end 0.12065 -0.2794)
			(stroke
				(width 0.1)
				(type default)
			)
			(layer "F.Fab")
		)
		(fp_line
			(start 0.120396 0.2794)
			(end -0.12065 0.2794)
			(stroke
				(width 0.1)
				(type default)
			)
			(layer "F.Fab")
		)
		(fp_line
			(start -0.12065 0.2794)
			(end -0.12065 0.3048)
			(stroke
				(width 0.1)
				(type default)
			)
			(layer "F.Fab")
		)
		(fp_line
			(start 0.67945 0.3048)
			(end 0.120396 0.3048)
			(stroke
				(width 0.1)
				(type default)
			)
			(layer "F.Fab")
		)
		(fp_line
			(start 0.120396 0.3048)
			(end 0.120396 0.2794)
			(stroke
				(width 0.1)
				(type default)
			)
			(layer "F.Fab")
		)
		(fp_line
			(start -0.12065 0.3048)
			(end -0.67945 0.3048)
			(stroke
				(width 0.1)
				(type default)
			)
			(layer "F.Fab")
		)
		(fp_line
			(start -0.67945 0.3048)
			(end -0.67945 -0.305054)
			(stroke
				(width 0.1)
				(type default)
			)
			(layer "F.Fab")
		)
		(pad "1" smd circle
			(at -0.40005 0 90)
			(size 0 0)
			(layers "F.Cu" "F.Mask" "F.Paste")
			(net "GPU_FPGA_EROT_RECOV_BUF_R_N")
		)
		(pad "2" smd circle
			(at 0.40005 0 90)
			(size 0 0)
			(layers "F.Cu" "F.Mask" "F.Paste")
			(net "GPU_FPGA_EROT_RECOV_BUF_N")
		)
	)
	(footprint ""
		(layer "F.Cu")
		(at 98.13036 -412.171388 180)
		(property "Reference" "R4543"
			(at 0 0 180)
			(layer "F.SilkS")
			(hide yes)
			(effects
				(font
					(size 1.27 1.27)
				)
			)
		)
		(property "Value" ""
			(at 0 0 180)
			(layer "F.Fab")
			(effects
				(font
					(size 1.27 1.27)
				)
			)
		)
		(duplicate_pad_numbers_are_jumpers no)
		(fp_line
			(start 0.7874 0.4064)
			(end -0.7874 0.4064)
			(stroke
				(width 0.1524)
				(type default)
			)
			(layer "F.SilkS")
		)
		(fp_line
			(start 0.7874 -0.4064)
			(end 0.7874 0.4064)
			(stroke
				(width 0.1524)
				(type default)
			)
			(layer "F.SilkS")
		)
		(fp_line
			(start -0.7874 0.4064)
			(end -0.7874 -0.4064)
			(stroke
				(width 0.1524)
				(type default)
			)
			(layer "F.SilkS")
		)
		(fp_line
			(start -0.7874 -0.4064)
			(end 0.7874 -0.4064)
			(stroke
				(width 0.1524)
				(type default)
			)
			(layer "F.SilkS")
		)
		(fp_line
			(start 0.67945 0.3048)
			(end 0.120396 0.3048)
			(stroke
				(width 0.1)
				(type default)
			)
			(layer "F.Fab")
		)
		(fp_line
			(start 0.67945 -0.3048)
			(end 0.67945 0.3048)
			(stroke
				(width 0.1)
				(type default)
			)
			(layer "F.Fab")
		)
		(fp_line
			(start 0.12065 -0.2794)
			(end 0.12065 -0.3048)
			(stroke
				(width 0.1)
				(type default)
			)
			(layer "F.Fab")
		)
		(fp_line
			(start 0.12065 -0.3048)
			(end 0.67945 -0.3048)
			(stroke
				(width 0.1)
				(type default)
			)
			(layer "F.Fab")
		)
		(fp_line
			(start 0.120396 0.3048)
			(end 0.120396 0.2794)
			(stroke
				(width 0.1)
				(type default)
			)
			(layer "F.Fab")
		)
		(fp_line
			(start 0.120396 0.2794)
			(end -0.12065 0.2794)
			(stroke
				(width 0.1)
				(type default)
			)
			(layer "F.Fab")
		)
		(fp_line
			(start -0.12065 0.3048)
			(end -0.67945 0.3048)
			(stroke
				(width 0.1)
				(type default)
			)
			(layer "F.Fab")
		)
		(fp_line
			(start -0.12065 0.2794)
			(end -0.12065 0.3048)
			(stroke
				(width 0.1)
				(type default)
			)
			(layer "F.Fab")
		)
		(fp_line
			(start -0.12065 -0.2794)
			(end 0.12065 -0.2794)
			(stroke
				(width 0.1)
				(type default)
			)
			(layer "F.Fab")
		)
		(fp_line
			(start -0.12065 -0.305054)
			(end -0.12065 -0.2794)
			(stroke
				(width 0.1)
				(type default)
			)
			(layer "F.Fab")
		)
		(fp_line
			(start -0.67945 0.3048)
			(end -0.67945 -0.305054)
			(stroke
				(width 0.1)
				(type default)
			)
			(layer "F.Fab")
		)
		(fp_line
			(start -0.67945 -0.305054)
			(end -0.12065 -0.305054)
			(stroke
				(width 0.1)
				(type default)
			)
			(layer "F.Fab")
		)
		(pad "1" smd circle
			(at -0.40005 0 180)
			(size 0 0)
			(layers "F.Cu" "F.Mask" "F.Paste")
			(net "P3V3_AUX")
		)
		(pad "2" smd circle
			(at 0.40005 0 180)
			(size 0 0)
			(layers "F.Cu" "F.Mask" "F.Paste")
			(net "HGX_DETECT_N")
		)
	)
	(footprint ""
		(layer "F.Cu")
		(at 437.242966 -124.680726 180)
		(property "Reference" "R2400"
			(at 0 0 180)
			(layer "F.SilkS")
			(hide yes)
			(effects
				(font
					(size 1.27 1.27)
				)
			)
		)
		(property "Value" ""
			(at 0 0 180)
			(layer "F.Fab")
			(effects
				(font
					(size 1.27 1.27)
				)
			)
		)
		(duplicate_pad_numbers_are_jumpers no)
		(fp_line
			(start 0.7874 0.4064)
			(end -0.7874 0.4064)
			(stroke
				(width 0.1524)
				(type default)
			)
			(layer "F.SilkS")
		)
		(fp_line
			(start 0.7874 -0.4064)
			(end 0.7874 0.4064)
			(stroke
				(width 0.1524)
				(type default)
			)
			(layer "F.SilkS")
		)
		(fp_line
			(start -0.7874 0.4064)
			(end -0.7874 -0.4064)
			(stroke
				(width 0.1524)
				(type default)
			)
			(layer "F.SilkS")
		)
		(fp_line
			(start -0.7874 -0.4064)
			(end 0.7874 -0.4064)
			(stroke
				(width 0.1524)
				(type default)
			)
			(layer "F.SilkS")
		)
		(fp_line
			(start 0.67945 0.3048)
			(end 0.120396 0.3048)
			(stroke
				(width 0.1)
				(type default)
			)
			(layer "F.Fab")
		)
		(fp_line
			(start 0.67945 -0.3048)
			(end 0.67945 0.3048)
			(stroke
				(width 0.1)
				(type default)
			)
			(layer "F.Fab")
		)
		(fp_line
			(start 0.12065 -0.2794)
			(end 0.12065 -0.3048)
			(stroke
				(width 0.1)
				(type default)
			)
			(layer "F.Fab")
		)
		(fp_line
			(start 0.12065 -0.3048)
			(end 0.67945 -0.3048)
			(stroke
				(width 0.1)
				(type default)
			)
			(layer "F.Fab")
		)
		(fp_line
			(start 0.120396 0.3048)
			(end 0.120396 0.2794)
			(stroke
				(width 0.1)
				(type default)
			)
			(layer "F.Fab")
		)
		(fp_line
			(start 0.120396 0.2794)
			(end -0.12065 0.2794)
			(stroke
				(width 0.1)
				(type default)
			)
			(layer "F.Fab")
		)
		(fp_line
			(start -0.12065 0.3048)
			(end -0.67945 0.3048)
			(stroke
				(width 0.1)
				(type default)
			)
			(layer "F.Fab")
		)
		(fp_line
			(start -0.12065 0.2794)
			(end -0.12065 0.3048)
			(stroke
				(width 0.1)
				(type default)
			)
			(layer "F.Fab")
		)
		(fp_line
			(start -0.12065 -0.2794)
			(end 0.12065 -0.2794)
			(stroke
				(width 0.1)
				(type default)
			)
			(layer "F.Fab")
		)
		(fp_line
			(start -0.12065 -0.305054)
			(end -0.12065 -0.2794)
			(stroke
				(width 0.1)
				(type default)
			)
			(layer "F.Fab")
		)
		(fp_line
			(start -0.67945 0.3048)
			(end -0.67945 -0.305054)
			(stroke
				(width 0.1)
				(type default)
			)
			(layer "F.Fab")
		)
		(fp_line
			(start -0.67945 -0.305054)
			(end -0.12065 -0.305054)
			(stroke
				(width 0.1)
				(type default)
			)
			(layer "F.Fab")
		)
		(pad "1" smd circle
			(at -0.40005 0 180)
			(size 0 0)
			(layers "F.Cu" "F.Mask" "F.Paste")
			(net "SVID_DIO1_CPU0_R")
		)
		(pad "2" smd circle
			(at 0.40005 0 180)
			(size 0 0)
			(layers "F.Cu" "F.Mask" "F.Paste")
			(net "SVID_DIO_PVCCD_HV_CPU0_R")
		)
	)
	(footprint ""
		(layer "F.Cu")
		(at 77.77226 -128.8161)
		(property "Reference" "ME2"
			(at -9.652 -9.540748 0)
			(unlocked yes)
			(layer "F.SilkS")
			(effects
				(font
					(size 0.7874 0.5842)
					(thickness 0.1524)
				)
				(justify left)
			)
		)
		(property "Value" ""
			(at 0 0 0)
			(layer "F.Fab")
			(effects
				(font
					(size 1.27 1.27)
				)
			)
		)
		(duplicate_pad_numbers_are_jumpers no)
		(zone
			(layer "F.Cu")
			(hatch none 0.5)
			(connect_pads
				(clearance 0)
			)
			(min_thickness 0.25)
			(keepout
				(tracks allowed)
				(vias allowed)
				(pads allowed)
				(copperpour allowed)
				(footprints not_allowed)
			)
			(placement
				(enabled no)
				(sheetname "")
			)
			(fill
				(thermal_gap 0.5)
				(thermal_bridge_width 0.5)
				(island_removal_mode 0)
			)
			(polygon
				(pts
					(arc
						(start 87.77224 -128.8161)
						(mid 67.77228 -128.8161)
						(end 87.77224 -128.8161)
					)
				)
			)
		)
	)
	(footprint ""
		(layer "F.Cu")
		(at 404.006812 -57.791604)
		(property "Reference" "R780"
			(at 0 0 0)
			(layer "F.SilkS")
			(hide yes)
			(effects
				(font
					(size 1.27 1.27)
				)
			)
		)
		(property "Value" ""
			(at 0 0 0)
			(layer "F.Fab")
			(effects
				(font
					(size 1.27 1.27)
				)
			)
		)
		(duplicate_pad_numbers_are_jumpers no)
		(fp_line
			(start -0.7874 -0.4064)
			(end 0.7874 -0.4064)
			(stroke
				(width 0.1524)
				(type default)
			)
			(layer "F.SilkS")
		)
		(fp_line
			(start -0.7874 0.4064)
			(end -0.7874 -0.4064)
			(stroke
				(width 0.1524)
				(type default)
			)
			(layer "F.SilkS")
		)
		(fp_line
			(start 0.7874 -0.4064)
			(end 0.7874 0.4064)
			(stroke
				(width 0.1524)
				(type default)
			)
			(layer "F.SilkS")
		)
		(fp_line
			(start 0.7874 0.4064)
			(end -0.7874 0.4064)
			(stroke
				(width 0.1524)
				(type default)
			)
			(layer "F.SilkS")
		)
		(fp_line
			(start -0.67945 -0.305054)
			(end -0.12065 -0.305054)
			(stroke
				(width 0.1)
				(type default)
			)
			(layer "F.Fab")
		)
		(fp_line
			(start -0.67945 0.3048)
			(end -0.67945 -0.305054)
			(stroke
				(width 0.1)
				(type default)
			)
			(layer "F.Fab")
		)
		(fp_line
			(start -0.12065 -0.305054)
			(end -0.12065 -0.2794)
			(stroke
				(width 0.1)
				(type default)
			)
			(layer "F.Fab")
		)
		(fp_line
			(start -0.12065 -0.2794)
			(end 0.12065 -0.2794)
			(stroke
				(width 0.1)
				(type default)
			)
			(layer "F.Fab")
		)
		(fp_line
			(start -0.12065 0.2794)
			(end -0.12065 0.3048)
			(stroke
				(width 0.1)
				(type default)
			)
			(layer "F.Fab")
		)
		(fp_line
			(start -0.12065 0.3048)
			(end -0.67945 0.3048)
			(stroke
				(width 0.1)
				(type default)
			)
			(layer "F.Fab")
		)
		(fp_line
			(start 0.120396 0.2794)
			(end -0.12065 0.2794)
			(stroke
				(width 0.1)
				(type default)
			)
			(layer "F.Fab")
		)
		(fp_line
			(start 0.120396 0.3048)
			(end 0.120396 0.2794)
			(stroke
				(width 0.1)
				(type default)
			)
			(layer "F.Fab")
		)
		(fp_line
			(start 0.12065 -0.3048)
			(end 0.67945 -0.3048)
			(stroke
				(width 0.1)
				(type default)
			)
			(layer "F.Fab")
		)
		(fp_line
			(start 0.12065 -0.2794)
			(end 0.12065 -0.3048)
			(stroke
				(width 0.1)
				(type default)
			)
			(layer "F.Fab")
		)
		(fp_line
			(start 0.67945 -0.3048)
			(end 0.67945 0.3048)
			(stroke
				(width 0.1)
				(type default)
			)
			(layer "F.Fab")
		)
		(fp_line
			(start 0.67945 0.3048)
			(end 0.120396 0.3048)
			(stroke
				(width 0.1)
				(type default)
			)
			(layer "F.Fab")
		)
		(pad "1" smd circle
			(at -0.40005 0)
			(size 0 0)
			(layers "F.Cu" "F.Mask" "F.Paste")
			(net "FM_CPU_FBRK_DEBUG_N")
		)
		(pad "2" smd circle
			(at 0.40005 0)
			(size 0 0)
			(layers "F.Cu" "F.Mask" "F.Paste")
			(net "FM_CPU_FBRK_DEBUG_R_N")
		)
	)
	(footprint ""
		(layer "F.Cu")
		(at 352.839274 -343.902284 90)
		(property "Reference" "PC324"
			(at 0 0 90)
			(layer "F.SilkS")
			(hide yes)
			(effects
				(font
					(size 1.27 1.27)
				)
			)
		)
		(property "Value" ""
			(at 0 0 90)
			(layer "F.Fab")
			(effects
				(font
					(size 1.27 1.27)
				)
			)
		)
		(duplicate_pad_numbers_are_jumpers no)
		(fp_line
			(start -3.400044 1.249934)
			(end 3.400044 1.249934)
			(stroke
				(width 0.1524)
				(type default)
			)
			(layer "F.SilkS")
		)
		(fp_circle
			(center 0 1.249934)
			(end 0 4.649978)
			(stroke
				(width 0.1524)
				(type default)
			)
			(fill no)
			(layer "F.SilkS")
		)
		(fp_poly
			(pts
				(arc
					(start -3.400044 1.249934)
					(mid 0 4.649978)
					(end 3.400044 1.249934)
				)
			)
			(stroke
				(width 0)
				(type default)
			)
			(fill yes)
			(layer "F.SilkS")
		)
		(fp_circle
			(center 0 1.249934)
			(end 0 4.649978)
			(stroke
				(width 0.1)
				(type default)
			)
			(fill no)
			(layer "F.Fab")
		)
		(pad "1" thru_hole rect
			(at 0 0 90)
			(size 1.524 1.524)
			(drill 1.016)
			(layers "*.Cu" "*.Mask")
			(remove_unused_layers no)
			(net "SW_P12V_PVCCIN_CPU0_FLT")
			(clearance 0)
			(padstack
				(mode front_inner_back)
				(layer "Inner"
					(shape circle)
					(size 1.524 1.524)
					(clearance 0)
				)
				(layer "B.Cu"
					(shape rect)
					(size 1.524 1.524)
					(clearance 0)
				)
			)
		)
		(pad "2" thru_hole circle
			(at 0 2.500122 90)
			(size 1.524 1.524)
			(drill 1.016)
			(layers "*.Cu" "*.Mask")
			(remove_unused_layers no)
			(net "GND")
			(clearance 0)
		)
	)
)
